(kicad_pcb
	(version 20260206)
	(generator "pcbnew")
	(generator_version "10.0")
	(general
		(thickness 1.6)
		(legacy_teardrops no)
	)
	(paper "A4")
	(title_block
		(title "01162023_DA0F0TEBIF0_F0T_Expander_BD_F_brd_V02_OCP.brd")
		(comment 1 "Grand Teton / footprints 7629-7637 of 9728")
	)
	(layers
		(0 "F.Cu" signal "TOP")
		(4 "In1.Cu" signal "GND")
		(6 "In2.Cu" signal "VCC")
		(8 "In3.Cu" signal "VCC1")
		(10 "In4.Cu" signal "GND1")
		(12 "In5.Cu" signal "IN1")
		(14 "In6.Cu" signal "GND2")
		(16 "In7.Cu" signal "IN2")
		(18 "In8.Cu" signal "GND3")
		(20 "In9.Cu" signal "IN3")
		(22 "In10.Cu" signal "GND4")
		(24 "In11.Cu" signal "IN4")
		(26 "In12.Cu" signal "GND5")
		(28 "In13.Cu" signal "IN5")
		(30 "In14.Cu" signal "GND6")
		(32 "In15.Cu" signal "IN6")
		(34 "In16.Cu" signal "GND7")
		(2 "B.Cu" signal "BOTTOM")
		(9 "F.Adhes" user "F.Adhesive")
		(11 "B.Adhes" user "B.Adhesive")
		(13 "F.Paste" user "Package Geometry/Pastemask Top")
		(15 "B.Paste" user "Package Geometry/Pastemask Bottom")
		(5 "F.SilkS" user "Ref Des/Silkscreen Top")
		(7 "B.SilkS" user "Ref Des/Silkscreen Bottom")
		(1 "F.Mask" user "Board Geometry/Soldermask Top")
		(3 "B.Mask" user "Board Geometry/Soldermask Bottom")
		(17 "Dwgs.User" user "User.Drawings")
		(19 "Cmts.User" user "User.Comments")
		(21 "Eco1.User" user "User.Eco1")
		(23 "Eco2.User" user "User.Eco2")
		(25 "Edge.Cuts" user "Board Geometry/Outline")
		(27 "Margin" user)
		(31 "F.CrtYd" user "Package Geometry/Place Bound Top")
		(29 "B.CrtYd" user "Package Geometry/Place Bound Bottom")
		(35 "F.Fab" user "Ref Des/Assembly Top")
		(33 "B.Fab" user "Ref Des/Assembly Bottom")
	)
	(footprint ""
		(layer "B.Cu")
		(at 349.290894 -308.613556 90)
		(property "Reference" "C1667"
			(at 0 0 90)
			(layer "B.SilkS")
			(hide yes)
			(effects
				(font
					(size 1.27 1.27)
				)
				(justify mirror)
			)
		)
		(property "Value" ""
			(at 0 0 90)
			(layer "B.Fab")
			(effects
				(font
					(size 1.27 1.27)
				)
				(justify mirror)
			)
		)
		(duplicate_pad_numbers_are_jumpers no)
		(fp_line
			(start 1.2954 -0.5842)
			(end -1.2954 -0.5842)
			(stroke
				(width 0.1524)
				(type default)
			)
			(layer "B.SilkS")
		)
		(fp_line
			(start -1.2954 -0.5842)
			(end -1.2954 0.5842)
			(stroke
				(width 0.1524)
				(type default)
			)
			(layer "B.SilkS")
		)
		(fp_line
			(start 1.2954 0.5842)
			(end 1.2954 -0.5842)
			(stroke
				(width 0.1524)
				(type default)
			)
			(layer "B.SilkS")
		)
		(fp_line
			(start -1.2954 0.5842)
			(end 1.2954 0.5842)
			(stroke
				(width 0.1524)
				(type default)
			)
			(layer "B.SilkS")
		)
		(fp_line
			(start 0.8636 -0.4572)
			(end -0.8636 -0.4572)
			(stroke
				(width 0.1)
				(type default)
			)
			(layer "B.Fab")
		)
		(fp_line
			(start -0.8636 -0.4572)
			(end -0.8636 -0.4064)
			(stroke
				(width 0.1)
				(type default)
			)
			(layer "B.Fab")
		)
		(fp_line
			(start 1.1938 -0.4064)
			(end 0.8636 -0.4064)
			(stroke
				(width 0.1)
				(type default)
			)
			(layer "B.Fab")
		)
		(fp_line
			(start 0.8636 -0.4064)
			(end 0.8636 -0.4572)
			(stroke
				(width 0.1)
				(type default)
			)
			(layer "B.Fab")
		)
		(fp_line
			(start -0.8636 -0.4064)
			(end -1.1938 -0.4064)
			(stroke
				(width 0.1)
				(type default)
			)
			(layer "B.Fab")
		)
		(fp_line
			(start -1.1938 -0.4064)
			(end -1.1938 0.4064)
			(stroke
				(width 0.1)
				(type default)
			)
			(layer "B.Fab")
		)
		(fp_line
			(start 1.1938 0.4064)
			(end 1.1938 -0.4064)
			(stroke
				(width 0.1)
				(type default)
			)
			(layer "B.Fab")
		)
		(fp_line
			(start 0.8636 0.4064)
			(end 1.1938 0.4064)
			(stroke
				(width 0.1)
				(type default)
			)
			(layer "B.Fab")
		)
		(fp_line
			(start -0.8636 0.4064)
			(end -0.8636 0.4572)
			(stroke
				(width 0.1)
				(type default)
			)
			(layer "B.Fab")
		)
		(fp_line
			(start -1.1938 0.4064)
			(end -0.8636 0.4064)
			(stroke
				(width 0.1)
				(type default)
			)
			(layer "B.Fab")
		)
		(fp_line
			(start 0.8636 0.4572)
			(end 0.8636 0.4064)
			(stroke
				(width 0.1)
				(type default)
			)
			(layer "B.Fab")
		)
		(fp_line
			(start -0.8636 0.4572)
			(end 0.8636 0.4572)
			(stroke
				(width 0.1)
				(type default)
			)
			(layer "B.Fab")
		)
		(pad "1" smd rect
			(at 0.7366 0)
			(size 0.7112 0.8128)
			(layers "B.Cu" "B.Mask" "B.Paste")
			(net "P0V8_SERDES_VDDA_PEX2")
		)
		(pad "2" smd rect
			(at -0.7366 0)
			(size 0.7112 0.8128)
			(layers "B.Cu" "B.Mask" "B.Paste")
			(net "GND")
		)
	)
	(footprint ""
		(layer "B.Cu")
		(at 410.02204 -296.3926)
		(property "Reference" "C1897"
			(at 0 0 0)
			(layer "B.SilkS")
			(hide yes)
			(effects
				(font
					(size 1.27 1.27)
				)
				(justify mirror)
			)
		)
		(property "Value" ""
			(at 0 0 0)
			(layer "B.Fab")
			(effects
				(font
					(size 1.27 1.27)
				)
				(justify mirror)
			)
		)
		(duplicate_pad_numbers_are_jumpers no)
		(fp_line
			(start -0.299974 -0.150114)
			(end -0.299974 0.150114)
			(stroke
				(width 0.1)
				(type default)
			)
			(layer "B.Fab")
		)
		(fp_line
			(start -0.299974 0.150114)
			(end 0.299974 0.150114)
			(stroke
				(width 0.1)
				(type default)
			)
			(layer "B.Fab")
		)
		(fp_line
			(start 0.299974 -0.150114)
			(end -0.299974 -0.150114)
			(stroke
				(width 0.1)
				(type default)
			)
			(layer "B.Fab")
		)
		(fp_line
			(start 0.299974 0.150114)
			(end 0.299974 -0.150114)
			(stroke
				(width 0.1)
				(type default)
			)
			(layer "B.Fab")
		)
		(pad "1" smd rect
			(at 0.2667 0 180)
			(size 0.3048 0.381)
			(layers "B.Cu" "B.Mask" "B.Paste")
			(net "P0V8_PEX3")
		)
		(pad "2" smd rect
			(at -0.2667 0 180)
			(size 0.3048 0.381)
			(layers "B.Cu" "B.Mask" "B.Paste")
			(net "GND")
		)
	)
	(footprint ""
		(layer "B.Cu")
		(at 56.799988 -303.499774 -90)
		(property "Reference" "C2918"
			(at 0 0 90)
			(layer "B.SilkS")
			(hide yes)
			(effects
				(font
					(size 1.27 1.27)
				)
				(justify mirror)
			)
		)
		(property "Value" ""
			(at 0 0 90)
			(layer "B.Fab")
			(effects
				(font
					(size 1.27 1.27)
				)
				(justify mirror)
			)
		)
		(duplicate_pad_numbers_are_jumpers no)
		(fp_line
			(start -0.299974 0.150114)
			(end 0.299974 0.150114)
			(stroke
				(width 0.1)
				(type default)
			)
			(layer "B.Fab")
		)
		(fp_line
			(start 0.299974 0.150114)
			(end 0.299974 -0.150114)
			(stroke
				(width 0.1)
				(type default)
			)
			(layer "B.Fab")
		)
		(fp_line
			(start -0.299974 -0.150114)
			(end -0.299974 0.150114)
			(stroke
				(width 0.1)
				(type default)
			)
			(layer "B.Fab")
		)
		(fp_line
			(start 0.299974 -0.150114)
			(end -0.299974 -0.150114)
			(stroke
				(width 0.1)
				(type default)
			)
			(layer "B.Fab")
		)
		(pad "1" smd rect
			(at 0.2667 0 90)
			(size 0.3048 0.381)
			(layers "B.Cu" "B.Mask" "B.Paste")
			(net "P1V25_PEX0")
		)
		(pad "2" smd rect
			(at -0.2667 0 90)
			(size 0.3048 0.381)
			(layers "B.Cu" "B.Mask" "B.Paste")
			(net "GND")
		)
	)
	(footprint ""
		(layer "B.Cu")
		(at 182.87492 -305.399948 -90)
		(property "Reference" "C3137"
			(at 0 0 90)
			(layer "B.SilkS")
			(hide yes)
			(effects
				(font
					(size 1.27 1.27)
				)
				(justify mirror)
			)
		)
		(property "Value" ""
			(at 0 0 90)
			(layer "B.Fab")
			(effects
				(font
					(size 1.27 1.27)
				)
				(justify mirror)
			)
		)
		(duplicate_pad_numbers_are_jumpers no)
		(fp_line
			(start -0.299974 0.150114)
			(end 0.299974 0.150114)
			(stroke
				(width 0.1)
				(type default)
			)
			(layer "B.Fab")
		)
		(fp_line
			(start 0.299974 0.150114)
			(end 0.299974 -0.150114)
			(stroke
				(width 0.1)
				(type default)
			)
			(layer "B.Fab")
		)
		(fp_line
			(start -0.299974 -0.150114)
			(end -0.299974 0.150114)
			(stroke
				(width 0.1)
				(type default)
			)
			(layer "B.Fab")
		)
		(fp_line
			(start 0.299974 -0.150114)
			(end -0.299974 -0.150114)
			(stroke
				(width 0.1)
				(type default)
			)
			(layer "B.Fab")
		)
		(pad "1" smd rect
			(at 0.2667 0 90)
			(size 0.3048 0.381)
			(layers "B.Cu" "B.Mask" "B.Paste")
			(net "P1V25_SERDES_VDDPLL_PEX1")
		)
		(pad "2" smd rect
			(at -0.2667 0 90)
			(size 0.3048 0.381)
			(layers "B.Cu" "B.Mask" "B.Paste")
			(net "GND")
		)
	)
	(footprint ""
		(layer "B.Cu")
		(at 170.049952 -303.499774 -90)
		(property "Reference" "C3088"
			(at 0 0 90)
			(layer "B.SilkS")
			(hide yes)
			(effects
				(font
					(size 1.27 1.27)
				)
				(justify mirror)
			)
		)
		(property "Value" ""
			(at 0 0 90)
			(layer "B.Fab")
			(effects
				(font
					(size 1.27 1.27)
				)
				(justify mirror)
			)
		)
		(duplicate_pad_numbers_are_jumpers no)
		(fp_line
			(start -0.299974 0.150114)
			(end 0.299974 0.150114)
			(stroke
				(width 0.1)
				(type default)
			)
			(layer "B.Fab")
		)
		(fp_line
			(start 0.299974 0.150114)
			(end 0.299974 -0.150114)
			(stroke
				(width 0.1)
				(type default)
			)
			(layer "B.Fab")
		)
		(fp_line
			(start -0.299974 -0.150114)
			(end -0.299974 0.150114)
			(stroke
				(width 0.1)
				(type default)
			)
			(layer "B.Fab")
		)
		(fp_line
			(start 0.299974 -0.150114)
			(end -0.299974 -0.150114)
			(stroke
				(width 0.1)
				(type default)
			)
			(layer "B.Fab")
		)
		(pad "1" smd rect
			(at 0.2667 0 90)
			(size 0.3048 0.381)
			(layers "B.Cu" "B.Mask" "B.Paste")
			(net "P1V25_PEX1")
		)
		(pad "2" smd rect
			(at -0.2667 0 90)
			(size 0.3048 0.381)
			(layers "B.Cu" "B.Mask" "B.Paste")
			(net "GND")
		)
	)
	(footprint ""
		(layer "B.Cu")
		(at 156.273754 -295.79824 180)
		(property "Reference" "R3456"
			(at 0 0 0)
			(layer "B.SilkS")
			(hide yes)
			(effects
				(font
					(size 1.27 1.27)
				)
				(justify mirror)
			)
		)
		(property "Value" ""
			(at 0 0 0)
			(layer "B.Fab")
			(effects
				(font
					(size 1.27 1.27)
				)
				(justify mirror)
			)
		)
		(duplicate_pad_numbers_are_jumpers no)
		(fp_line
			(start 0.7874 0.4064)
			(end 0.7874 -0.4064)
			(stroke
				(width 0.1524)
				(type default)
			)
			(layer "B.SilkS")
		)
		(fp_line
			(start 0.7874 -0.4064)
			(end -0.7874 -0.4064)
			(stroke
				(width 0.1524)
				(type default)
			)
			(layer "B.SilkS")
		)
		(fp_line
			(start -0.7874 0.4064)
			(end 0.7874 0.4064)
			(stroke
				(width 0.1524)
				(type default)
			)
			(layer "B.SilkS")
		)
		(fp_line
			(start -0.7874 -0.4064)
			(end -0.7874 0.4064)
			(stroke
				(width 0.1524)
				(type default)
			)
			(layer "B.SilkS")
		)
		(fp_line
			(start 0.67945 0.3048)
			(end 0.67945 -0.305054)
			(stroke
				(width 0.1)
				(type default)
			)
			(layer "B.Fab")
		)
		(fp_line
			(start 0.67945 -0.305054)
			(end 0.12065 -0.305054)
			(stroke
				(width 0.1)
				(type default)
			)
			(layer "B.Fab")
		)
		(fp_line
			(start 0.12065 0.3048)
			(end 0.67945 0.3048)
			(stroke
				(width 0.1)
				(type default)
			)
			(layer "B.Fab")
		)
		(fp_line
			(start 0.12065 0.2794)
			(end 0.12065 0.3048)
			(stroke
				(width 0.1)
				(type default)
			)
			(layer "B.Fab")
		)
		(fp_line
			(start 0.12065 -0.2794)
			(end -0.12065 -0.2794)
			(stroke
				(width 0.1)
				(type default)
			)
			(layer "B.Fab")
		)
		(fp_line
			(start 0.12065 -0.305054)
			(end 0.12065 -0.2794)
			(stroke
				(width 0.1)
				(type default)
			)
			(layer "B.Fab")
		)
		(fp_line
			(start -0.120396 0.3048)
			(end -0.120396 0.2794)
			(stroke
				(width 0.1)
				(type default)
			)
			(layer "B.Fab")
		)
		(fp_line
			(start -0.120396 0.2794)
			(end 0.12065 0.2794)
			(stroke
				(width 0.1)
				(type default)
			)
			(layer "B.Fab")
		)
		(fp_line
			(start -0.12065 -0.2794)
			(end -0.12065 -0.3048)
			(stroke
				(width 0.1)
				(type default)
			)
			(layer "B.Fab")
		)
		(fp_line
			(start -0.12065 -0.3048)
			(end -0.67945 -0.3048)
			(stroke
				(width 0.1)
				(type default)
			)
			(layer "B.Fab")
		)
		(fp_line
			(start -0.67945 0.3048)
			(end -0.120396 0.3048)
			(stroke
				(width 0.1)
				(type default)
			)
			(layer "B.Fab")
		)
		(fp_line
			(start -0.67945 -0.3048)
			(end -0.67945 0.3048)
			(stroke
				(width 0.1)
				(type default)
			)
			(layer "B.Fab")
		)
		(pad "1" smd circle
			(at 0.40005 0)
			(size 0 0)
			(layers "B.Cu" "B.Mask" "B.Paste")
			(net "SPI_PEX1_SDIO0_R")
		)
		(pad "2" smd circle
			(at -0.40005 0)
			(size 0 0)
			(layers "B.Cu" "B.Mask" "B.Paste")
			(net "SPI_PEX1_SDIO0")
		)
	)
	(footprint ""
		(layer "B.Cu")
		(at 333.909416 -323.15531 -90)
		(property "Reference" "R6517"
			(at 0 0 90)
			(layer "B.SilkS")
			(hide yes)
			(effects
				(font
					(size 1.27 1.27)
				)
				(justify mirror)
			)
		)
		(property "Value" ""
			(at 0 0 90)
			(layer "B.Fab")
			(effects
				(font
					(size 1.27 1.27)
				)
				(justify mirror)
			)
		)
		(duplicate_pad_numbers_are_jumpers no)
		(fp_line
			(start -0.7874 0.4064)
			(end 0.7874 0.4064)
			(stroke
				(width 0.1524)
				(type default)
			)
			(layer "B.SilkS")
		)
		(fp_line
			(start 0.7874 0.4064)
			(end 0.7874 -0.4064)
			(stroke
				(width 0.1524)
				(type default)
			)
			(layer "B.SilkS")
		)
		(fp_line
			(start -0.7874 -0.4064)
			(end -0.7874 0.4064)
			(stroke
				(width 0.1524)
				(type default)
			)
			(layer "B.SilkS")
		)
		(fp_line
			(start 0.7874 -0.4064)
			(end -0.7874 -0.4064)
			(stroke
				(width 0.1524)
				(type default)
			)
			(layer "B.SilkS")
		)
		(fp_line
			(start -0.67945 0.3048)
			(end -0.120396 0.3048)
			(stroke
				(width 0.1)
				(type default)
			)
			(layer "B.Fab")
		)
		(fp_line
			(start -0.120396 0.3048)
			(end -0.120396 0.2794)
			(stroke
				(width 0.1)
				(type default)
			)
			(layer "B.Fab")
		)
		(fp_line
			(start 0.12065 0.3048)
			(end 0.67945 0.3048)
			(stroke
				(width 0.1)
				(type default)
			)
			(layer "B.Fab")
		)
		(fp_line
			(start 0.67945 0.3048)
			(end 0.67945 -0.305054)
			(stroke
				(width 0.1)
				(type default)
			)
			(layer "B.Fab")
		)
		(fp_line
			(start -0.120396 0.2794)
			(end 0.12065 0.2794)
			(stroke
				(width 0.1)
				(type default)
			)
			(layer "B.Fab")
		)
		(fp_line
			(start 0.12065 0.2794)
			(end 0.12065 0.3048)
			(stroke
				(width 0.1)
				(type default)
			)
			(layer "B.Fab")
		)
		(fp_line
			(start -0.12065 -0.2794)
			(end -0.12065 -0.3048)
			(stroke
				(width 0.1)
				(type default)
			)
			(layer "B.Fab")
		)
		(fp_line
			(start 0.12065 -0.2794)
			(end -0.12065 -0.2794)
			(stroke
				(width 0.1)
				(type default)
			)
			(layer "B.Fab")
		)
		(fp_line
			(start -0.67945 -0.3048)
			(end -0.67945 0.3048)
			(stroke
				(width 0.1)
				(type default)
			)
			(layer "B.Fab")
		)
		(fp_line
			(start -0.12065 -0.3048)
			(end -0.67945 -0.3048)
			(stroke
				(width 0.1)
				(type default)
			)
			(layer "B.Fab")
		)
		(fp_line
			(start 0.12065 -0.305054)
			(end 0.12065 -0.2794)
			(stroke
				(width 0.1)
				(type default)
			)
			(layer "B.Fab")
		)
		(fp_line
			(start 0.67945 -0.305054)
			(end 0.12065 -0.305054)
			(stroke
				(width 0.1)
				(type default)
			)
			(layer "B.Fab")
		)
		(pad "1" smd circle
			(at 0.40005 0 90)
			(size 0 0)
			(layers "B.Cu" "B.Mask" "B.Paste")
			(net "P0V8_SERDES_VDDA_PEX2")
		)
		(pad "2" smd circle
			(at -0.40005 0 90)
			(size 0 0)
			(layers "B.Cu" "B.Mask" "B.Paste")
			(net "P0V8_SERDES_VDDA_PEX2_C10")
		)
	)
	(footprint ""
		(layer "B.Cu")
		(at 301.141384 -286.874966)
		(property "Reference" "C3344"
			(at 0 0 0)
			(layer "B.SilkS")
			(hide yes)
			(effects
				(font
					(size 1.27 1.27)
				)
				(justify mirror)
			)
		)
		(property "Value" ""
			(at 0 0 0)
			(layer "B.Fab")
			(effects
				(font
					(size 1.27 1.27)
				)
				(justify mirror)
			)
		)
		(duplicate_pad_numbers_are_jumpers no)
		(fp_line
			(start -0.299974 -0.150114)
			(end -0.299974 0.150114)
			(stroke
				(width 0.1)
				(type default)
			)
			(layer "B.Fab")
		)
		(fp_line
			(start -0.299974 0.150114)
			(end 0.299974 0.150114)
			(stroke
				(width 0.1)
				(type default)
			)
			(layer "B.Fab")
		)
		(fp_line
			(start 0.299974 -0.150114)
			(end -0.299974 -0.150114)
			(stroke
				(width 0.1)
				(type default)
			)
			(layer "B.Fab")
		)
		(fp_line
			(start 0.299974 0.150114)
			(end 0.299974 -0.150114)
			(stroke
				(width 0.1)
				(type default)
			)
			(layer "B.Fab")
		)
		(pad "1" smd rect
			(at 0.2667 0 180)
			(size 0.3048 0.381)
			(layers "B.Cu" "B.Mask" "B.Paste")
			(net "P1V8_VDDA_PEX2")
		)
		(pad "2" smd rect
			(at -0.2667 0 180)
			(size 0.3048 0.381)
			(layers "B.Cu" "B.Mask" "B.Paste")
			(net "GND")
		)
	)
	(footprint ""
		(layer "B.Cu")
		(at 336.27441 -308.613556 90)
		(property "Reference" "C4316"
			(at 0 0 90)
			(layer "B.SilkS")
			(hide yes)
			(effects
				(font
					(size 1.27 1.27)
				)
				(justify mirror)
			)
		)
		(property "Value" ""
			(at 0 0 90)
			(layer "B.Fab")
			(effects
				(font
					(size 1.27 1.27)
				)
				(justify mirror)
			)
		)
		(duplicate_pad_numbers_are_jumpers no)
		(fp_line
			(start 1.2954 -0.5842)
			(end -1.2954 -0.5842)
			(stroke
				(width 0.1524)
				(type default)
			)
			(layer "B.SilkS")
		)
		(fp_line
			(start -1.2954 -0.5842)
			(end -1.2954 0.5842)
			(stroke
				(width 0.1524)
				(type default)
			)
			(layer "B.SilkS")
		)
		(fp_line
			(start 1.2954 0.5842)
			(end 1.2954 -0.5842)
			(stroke
				(width 0.1524)
				(type default)
			)
			(layer "B.SilkS")
		)
		(fp_line
			(start -1.2954 0.5842)
			(end 1.2954 0.5842)
			(stroke
				(width 0.1524)
				(type default)
			)
			(layer "B.SilkS")
		)
		(fp_line
			(start 0.8636 -0.4572)
			(end -0.8636 -0.4572)
			(stroke
				(width 0.1)
				(type default)
			)
			(layer "B.Fab")
		)
		(fp_line
			(start -0.8636 -0.4572)
			(end -0.8636 -0.4064)
			(stroke
				(width 0.1)
				(type default)
			)
			(layer "B.Fab")
		)
		(fp_line
			(start 1.1938 -0.4064)
			(end 0.8636 -0.4064)
			(stroke
				(width 0.1)
				(type default)
			)
			(layer "B.Fab")
		)
		(fp_line
			(start 0.8636 -0.4064)
			(end 0.8636 -0.4572)
			(stroke
				(width 0.1)
				(type default)
			)
			(layer "B.Fab")
		)
		(fp_line
			(start -0.8636 -0.4064)
			(end -1.1938 -0.4064)
			(stroke
				(width 0.1)
				(type default)
			)
			(layer "B.Fab")
		)
		(fp_line
			(start -1.1938 -0.4064)
			(end -1.1938 0.4064)
			(stroke
				(width 0.1)
				(type default)
			)
			(layer "B.Fab")
		)
		(fp_line
			(start 1.1938 0.4064)
			(end 1.1938 -0.4064)
			(stroke
				(width 0.1)
				(type default)
			)
			(layer "B.Fab")
		)
		(fp_line
			(start 0.8636 0.4064)
			(end 1.1938 0.4064)
			(stroke
				(width 0.1)
				(type default)
			)
			(layer "B.Fab")
		)
		(fp_line
			(start -0.8636 0.4064)
			(end -0.8636 0.4572)
			(stroke
				(width 0.1)
				(type default)
			)
			(layer "B.Fab")
		)
		(fp_line
			(start -1.1938 0.4064)
			(end -0.8636 0.4064)
			(stroke
				(width 0.1)
				(type default)
			)
			(layer "B.Fab")
		)
		(fp_line
			(start 0.8636 0.4572)
			(end 0.8636 0.4064)
			(stroke
				(width 0.1)
				(type default)
			)
			(layer "B.Fab")
		)
		(fp_line
			(start -0.8636 0.4572)
			(end 0.8636 0.4572)
			(stroke
				(width 0.1)
				(type default)
			)
			(layer "B.Fab")
		)
		(pad "1" smd rect
			(at 0.7366 0)
			(size 0.7112 0.8128)
			(layers "B.Cu" "B.Mask" "B.Paste")
			(net "P0V8_PEX2")
		)
		(pad "2" smd rect
			(at -0.7366 0)
			(size 0.7112 0.8128)
			(layers "B.Cu" "B.Mask" "B.Paste")
			(net "GND")
		)
	)
)
